(kicad_pcb
	(version 20260206)
	(generator "pcbnew")
	(generator_version "10.0")
	(general
		(thickness 1.6)
		(legacy_teardrops no)
	)
	(paper "A4")
	(title_block
		(title "04192023_DAF0TMB3IC0_F0TG_MB_C_brd_V02_OCP.brd")
		(comment 1 "Grand Teton / footprints 2364-2370 of 8354")
	)
	(layers
		(0 "F.Cu" signal "TOP")
		(4 "In1.Cu" signal "GND")
		(6 "In2.Cu" signal "IN1")
		(8 "In3.Cu" signal "GND1")
		(10 "In4.Cu" signal "IN2")
		(12 "In5.Cu" signal "GND2")
		(14 "In6.Cu" signal "IN3")
		(16 "In7.Cu" signal "GND3")
		(18 "In8.Cu" signal "VCC")
		(20 "In9.Cu" signal "VCC1")
		(22 "In10.Cu" signal "GND4")
		(24 "In11.Cu" signal "IN4")
		(26 "In12.Cu" signal "GND5")
		(28 "In13.Cu" signal "IN5")
		(30 "In14.Cu" signal "GND6")
		(32 "In15.Cu" signal "IN6")
		(34 "In16.Cu" signal "GND7")
		(2 "B.Cu" signal "BOTTOM")
		(9 "F.Adhes" user "F.Adhesive")
		(11 "B.Adhes" user "B.Adhesive")
		(13 "F.Paste" user "Package Geometry/Pastemask Top")
		(15 "B.Paste" user "Package Geometry/Pastemask Bottom")
		(5 "F.SilkS" user "Ref Des/Silkscreen Top")
		(7 "B.SilkS" user "Ref Des/Silkscreen Bottom")
		(1 "F.Mask" user "Board Geometry/Soldermask Top")
		(3 "B.Mask" user "Board Geometry/Soldermask Bottom")
		(17 "Dwgs.User" user "User.Drawings")
		(19 "Cmts.User" user "User.Comments")
		(21 "Eco1.User" user "User.Eco1")
		(23 "Eco2.User" user "User.Eco2")
		(25 "Edge.Cuts" user "Board Geometry/Outline")
		(27 "Margin" user)
		(31 "F.CrtYd" user "Package Geometry/Place Bound Top")
		(29 "B.CrtYd" user "Package Geometry/Place Bound Bottom")
		(35 "F.Fab" user "Ref Des/Assembly Top")
		(33 "B.Fab" user "Ref Des/Assembly Bottom")
	)
	(footprint ""
		(layer "F.Cu")
		(at 455.01306 -41.105836 180)
		(property "Reference" "R4069"
			(at 0 0 180)
			(layer "F.SilkS")
			(hide yes)
			(effects
				(font
					(size 1.27 1.27)
				)
			)
		)
		(property "Value" ""
			(at 0 0 180)
			(layer "F.Fab")
			(effects
				(font
					(size 1.27 1.27)
				)
			)
		)
		(duplicate_pad_numbers_are_jumpers no)
		(fp_line
			(start 0.7874 0.4064)
			(end -0.7874 0.4064)
			(stroke
				(width 0.1524)
				(type default)
			)
			(layer "F.SilkS")
		)
		(fp_line
			(start 0.7874 -0.4064)
			(end 0.7874 0.4064)
			(stroke
				(width 0.1524)
				(type default)
			)
			(layer "F.SilkS")
		)
		(fp_line
			(start -0.7874 0.4064)
			(end -0.7874 -0.4064)
			(stroke
				(width 0.1524)
				(type default)
			)
			(layer "F.SilkS")
		)
		(fp_line
			(start -0.7874 -0.4064)
			(end 0.7874 -0.4064)
			(stroke
				(width 0.1524)
				(type default)
			)
			(layer "F.SilkS")
		)
		(fp_line
			(start 0.67945 0.3048)
			(end 0.120396 0.3048)
			(stroke
				(width 0.1)
				(type default)
			)
			(layer "F.Fab")
		)
		(fp_line
			(start 0.67945 -0.3048)
			(end 0.67945 0.3048)
			(stroke
				(width 0.1)
				(type default)
			)
			(layer "F.Fab")
		)
		(fp_line
			(start 0.12065 -0.2794)
			(end 0.12065 -0.3048)
			(stroke
				(width 0.1)
				(type default)
			)
			(layer "F.Fab")
		)
		(fp_line
			(start 0.12065 -0.3048)
			(end 0.67945 -0.3048)
			(stroke
				(width 0.1)
				(type default)
			)
			(layer "F.Fab")
		)
		(fp_line
			(start 0.120396 0.3048)
			(end 0.120396 0.2794)
			(stroke
				(width 0.1)
				(type default)
			)
			(layer "F.Fab")
		)
		(fp_line
			(start 0.120396 0.2794)
			(end -0.12065 0.2794)
			(stroke
				(width 0.1)
				(type default)
			)
			(layer "F.Fab")
		)
		(fp_line
			(start -0.12065 0.3048)
			(end -0.67945 0.3048)
			(stroke
				(width 0.1)
				(type default)
			)
			(layer "F.Fab")
		)
		(fp_line
			(start -0.12065 0.2794)
			(end -0.12065 0.3048)
			(stroke
				(width 0.1)
				(type default)
			)
			(layer "F.Fab")
		)
		(fp_line
			(start -0.12065 -0.2794)
			(end 0.12065 -0.2794)
			(stroke
				(width 0.1)
				(type default)
			)
			(layer "F.Fab")
		)
		(fp_line
			(start -0.12065 -0.305054)
			(end -0.12065 -0.2794)
			(stroke
				(width 0.1)
				(type default)
			)
			(layer "F.Fab")
		)
		(fp_line
			(start -0.67945 0.3048)
			(end -0.67945 -0.305054)
			(stroke
				(width 0.1)
				(type default)
			)
			(layer "F.Fab")
		)
		(fp_line
			(start -0.67945 -0.305054)
			(end -0.12065 -0.305054)
			(stroke
				(width 0.1)
				(type default)
			)
			(layer "F.Fab")
		)
		(pad "1" smd circle
			(at -0.40005 0 180)
			(size 0 0)
			(layers "F.Cu" "F.Mask" "F.Paste")
			(net "P3V3_OCP_EN_1_R")
		)
		(pad "2" smd circle
			(at 0.40005 0 180)
			(size 0 0)
			(layers "F.Cu" "F.Mask" "F.Paste")
			(net "GND")
		)
	)
	(footprint ""
		(layer "F.Cu")
		(at 447.44005 -40.420036)
		(property "Reference" "H6000"
			(at -2.5146 -3.58013 0)
			(unlocked yes)
			(layer "F.SilkS")
			(effects
				(font
					(size 0.7874 0.5842)
					(thickness 0.1524)
				)
				(justify left)
			)
		)
		(property "Value" ""
			(at 0 0 0)
			(layer "F.Fab")
			(effects
				(font
					(size 1.27 1.27)
				)
			)
		)
		(duplicate_pad_numbers_are_jumpers no)
		(pad "1" thru_hole circle
			(at 0 0)
			(size 6.1976 6.1976)
			(drill 3.7338)
			(layers "*.Cu" "*.Mask")
			(remove_unused_layers no)
			(net "GND")
			(clearance -0.9779)
			(padstack
				(mode front_inner_back)
				(layer "Inner"
					(shape circle)
					(size 5.5372 5.5372)
					(clearance -0.6477)
				)
				(layer "B.Cu"
					(shape circle)
					(size 6.1976 6.1976)
					(clearance -0.9779)
				)
			)
		)
	)
	(footprint ""
		(layer "F.Cu")
		(at 189.103 -129.377948 90)
		(property "Reference" "R258"
			(at 0 0 90)
			(layer "F.SilkS")
			(hide yes)
			(effects
				(font
					(size 1.27 1.27)
				)
			)
		)
		(property "Value" ""
			(at 0 0 90)
			(layer "F.Fab")
			(effects
				(font
					(size 1.27 1.27)
				)
			)
		)
		(duplicate_pad_numbers_are_jumpers no)
		(fp_line
			(start 0.7874 -0.4064)
			(end 0.7874 0.4064)
			(stroke
				(width 0.1524)
				(type default)
			)
			(layer "F.SilkS")
		)
		(fp_line
			(start -0.7874 -0.4064)
			(end 0.7874 -0.4064)
			(stroke
				(width 0.1524)
				(type default)
			)
			(layer "F.SilkS")
		)
		(fp_line
			(start 0.7874 0.4064)
			(end -0.7874 0.4064)
			(stroke
				(width 0.1524)
				(type default)
			)
			(layer "F.SilkS")
		)
		(fp_line
			(start -0.7874 0.4064)
			(end -0.7874 -0.4064)
			(stroke
				(width 0.1524)
				(type default)
			)
			(layer "F.SilkS")
		)
		(fp_line
			(start -0.12065 -0.305054)
			(end -0.12065 -0.2794)
			(stroke
				(width 0.1)
				(type default)
			)
			(layer "F.Fab")
		)
		(fp_line
			(start -0.67945 -0.305054)
			(end -0.12065 -0.305054)
			(stroke
				(width 0.1)
				(type default)
			)
			(layer "F.Fab")
		)
		(fp_line
			(start 0.67945 -0.3048)
			(end 0.67945 0.3048)
			(stroke
				(width 0.1)
				(type default)
			)
			(layer "F.Fab")
		)
		(fp_line
			(start 0.12065 -0.3048)
			(end 0.67945 -0.3048)
			(stroke
				(width 0.1)
				(type default)
			)
			(layer "F.Fab")
		)
		(fp_line
			(start 0.12065 -0.2794)
			(end 0.12065 -0.3048)
			(stroke
				(width 0.1)
				(type default)
			)
			(layer "F.Fab")
		)
		(fp_line
			(start -0.12065 -0.2794)
			(end 0.12065 -0.2794)
			(stroke
				(width 0.1)
				(type default)
			)
			(layer "F.Fab")
		)
		(fp_line
			(start 0.120396 0.2794)
			(end -0.12065 0.2794)
			(stroke
				(width 0.1)
				(type default)
			)
			(layer "F.Fab")
		)
		(fp_line
			(start -0.12065 0.2794)
			(end -0.12065 0.3048)
			(stroke
				(width 0.1)
				(type default)
			)
			(layer "F.Fab")
		)
		(fp_line
			(start 0.67945 0.3048)
			(end 0.120396 0.3048)
			(stroke
				(width 0.1)
				(type default)
			)
			(layer "F.Fab")
		)
		(fp_line
			(start 0.120396 0.3048)
			(end 0.120396 0.2794)
			(stroke
				(width 0.1)
				(type default)
			)
			(layer "F.Fab")
		)
		(fp_line
			(start -0.12065 0.3048)
			(end -0.67945 0.3048)
			(stroke
				(width 0.1)
				(type default)
			)
			(layer "F.Fab")
		)
		(fp_line
			(start -0.67945 0.3048)
			(end -0.67945 -0.305054)
			(stroke
				(width 0.1)
				(type default)
			)
			(layer "F.Fab")
		)
		(pad "1" smd circle
			(at -0.40005 0 90)
			(size 0 0)
			(layers "F.Cu" "F.Mask" "F.Paste")
			(net "FM_CPU0_HDT_CONN_TESTEN")
		)
		(pad "2" smd circle
			(at 0.40005 0 90)
			(size 0 0)
			(layers "F.Cu" "F.Mask" "F.Paste")
			(net "CPU0_HDT_CONN_TESTEN")
		)
	)
	(footprint ""
		(layer "F.Cu")
		(at 460.292196 -47.929546 -90)
		(property "Reference" "PC8008"
			(at 0 0 270)
			(layer "F.SilkS")
			(hide yes)
			(effects
				(font
					(size 1.27 1.27)
				)
			)
		)
		(property "Value" ""
			(at 0 0 270)
			(layer "F.Fab")
			(effects
				(font
					(size 1.27 1.27)
				)
			)
		)
		(duplicate_pad_numbers_are_jumpers no)
		(fp_line
			(start -1.2954 0.5842)
			(end -1.2954 -0.5842)
			(stroke
				(width 0.1524)
				(type default)
			)
			(layer "F.SilkS")
		)
		(fp_line
			(start 1.2954 0.5842)
			(end -1.2954 0.5842)
			(stroke
				(width 0.1524)
				(type default)
			)
			(layer "F.SilkS")
		)
		(fp_line
			(start -1.2954 -0.5842)
			(end 1.2954 -0.5842)
			(stroke
				(width 0.1524)
				(type default)
			)
			(layer "F.SilkS")
		)
		(fp_line
			(start 1.2954 -0.5842)
			(end 1.2954 0.5842)
			(stroke
				(width 0.1524)
				(type default)
			)
			(layer "F.SilkS")
		)
		(fp_line
			(start -0.8636 0.4572)
			(end -0.8636 0.4064)
			(stroke
				(width 0.1)
				(type default)
			)
			(layer "F.Fab")
		)
		(fp_line
			(start 0.8636 0.4572)
			(end -0.8636 0.4572)
			(stroke
				(width 0.1)
				(type default)
			)
			(layer "F.Fab")
		)
		(fp_line
			(start -1.1938 0.4064)
			(end -1.1938 -0.4064)
			(stroke
				(width 0.1)
				(type default)
			)
			(layer "F.Fab")
		)
		(fp_line
			(start -0.8636 0.4064)
			(end -1.1938 0.4064)
			(stroke
				(width 0.1)
				(type default)
			)
			(layer "F.Fab")
		)
		(fp_line
			(start 0.8636 0.4064)
			(end 0.8636 0.4572)
			(stroke
				(width 0.1)
				(type default)
			)
			(layer "F.Fab")
		)
		(fp_line
			(start 1.1938 0.4064)
			(end 0.8636 0.4064)
			(stroke
				(width 0.1)
				(type default)
			)
			(layer "F.Fab")
		)
		(fp_line
			(start -1.1938 -0.4064)
			(end -0.8636 -0.4064)
			(stroke
				(width 0.1)
				(type default)
			)
			(layer "F.Fab")
		)
		(fp_line
			(start -0.8636 -0.4064)
			(end -0.8636 -0.4572)
			(stroke
				(width 0.1)
				(type default)
			)
			(layer "F.Fab")
		)
		(fp_line
			(start 0.8636 -0.4064)
			(end 1.1938 -0.4064)
			(stroke
				(width 0.1)
				(type default)
			)
			(layer "F.Fab")
		)
		(fp_line
			(start 1.1938 -0.4064)
			(end 1.1938 0.4064)
			(stroke
				(width 0.1)
				(type default)
			)
			(layer "F.Fab")
		)
		(fp_line
			(start -0.8636 -0.4572)
			(end 0.8636 -0.4572)
			(stroke
				(width 0.1)
				(type default)
			)
			(layer "F.Fab")
		)
		(fp_line
			(start 0.8636 -0.4572)
			(end 0.8636 -0.4064)
			(stroke
				(width 0.1)
				(type default)
			)
			(layer "F.Fab")
		)
		(pad "1" smd rect
			(at -0.7366 0 180)
			(size 0.7112 0.8128)
			(layers "F.Cu" "F.Mask" "F.Paste")
			(net "P12V_AUX")
		)
		(pad "2" smd rect
			(at 0.7366 0 180)
			(size 0.7112 0.8128)
			(layers "F.Cu" "F.Mask" "F.Paste")
			(net "GND")
		)
	)
	(footprint ""
		(layer "F.Cu")
		(at 182.026306 -332.744572 -90)
		(property "Reference" "PC531"
			(at -4.13512 9.547352 90)
			(unlocked yes)
			(layer "F.SilkS")
			(effects
				(font
					(size 0.7874 0.5842)
					(thickness 0.1524)
				)
				(justify left)
			)
		)
		(property "Value" ""
			(at 0 0 270)
			(layer "F.Fab")
			(effects
				(font
					(size 1.27 1.27)
				)
			)
		)
		(duplicate_pad_numbers_are_jumpers no)
		(fp_line
			(start -1.988058 2.750058)
			(end 2.750058 2.750058)
			(stroke
				(width 0.1524)
				(type default)
			)
			(layer "F.SilkS")
		)
		(fp_line
			(start 2.750058 2.750058)
			(end 2.750058 0.9398)
			(stroke
				(width 0.1524)
				(type default)
			)
			(layer "F.SilkS")
		)
		(fp_line
			(start -2.750058 1.988058)
			(end -1.988058 2.750058)
			(stroke
				(width 0.1524)
				(type default)
			)
			(layer "F.SilkS")
		)
		(fp_line
			(start -2.750058 0.9398)
			(end -2.750058 1.988058)
			(stroke
				(width 0.1524)
				(type default)
			)
			(layer "F.SilkS")
		)
		(fp_line
			(start 2.750058 -0.9398)
			(end 2.750058 -2.750058)
			(stroke
				(width 0.1524)
				(type default)
			)
			(layer "F.SilkS")
		)
		(fp_line
			(start -2.750058 -1.988058)
			(end -2.750058 -0.9398)
			(stroke
				(width 0.1524)
				(type default)
			)
			(layer "F.SilkS")
		)
		(fp_line
			(start -1.988058 -2.750058)
			(end -2.750058 -1.988058)
			(stroke
				(width 0.1524)
				(type default)
			)
			(layer "F.SilkS")
		)
		(fp_line
			(start 2.750058 -2.750058)
			(end -1.988058 -2.750058)
			(stroke
				(width 0.1524)
				(type default)
			)
			(layer "F.SilkS")
		)
		(fp_line
			(start -2.750058 2.750058)
			(end 2.750058 2.750058)
			(stroke
				(width 0.1)
				(type default)
			)
			(layer "F.Fab")
		)
		(fp_line
			(start 2.750058 2.750058)
			(end 2.750058 -2.750058)
			(stroke
				(width 0.1)
				(type default)
			)
			(layer "F.Fab")
		)
		(fp_line
			(start -2.750058 -2.750058)
			(end -2.750058 2.750058)
			(stroke
				(width 0.1)
				(type default)
			)
			(layer "F.Fab")
		)
		(fp_line
			(start 2.750058 -2.750058)
			(end -2.750058 -2.750058)
			(stroke
				(width 0.1)
				(type default)
			)
			(layer "F.Fab")
		)
		(pad "1" smd rect
			(at -2.199894 0)
			(size 1.6002 3.0226)
			(layers "F.Cu" "F.Mask" "F.Paste")
			(net "PVDD11_S3_P1")
		)
		(pad "2" smd rect
			(at 2.199894 0)
			(size 1.6002 3.0226)
			(layers "F.Cu" "F.Mask" "F.Paste")
			(net "GND")
		)
	)
	(footprint ""
		(layer "F.Cu")
		(at 384.465576 -56.81345 -90)
		(property "Reference" "C605"
			(at 0 0 270)
			(layer "F.SilkS")
			(hide yes)
			(effects
				(font
					(size 1.27 1.27)
				)
			)
		)
		(property "Value" ""
			(at 0 0 270)
			(layer "F.Fab")
			(effects
				(font
					(size 1.27 1.27)
				)
			)
		)
		(duplicate_pad_numbers_are_jumpers no)
		(fp_line
			(start -0.7874 0.4064)
			(end -0.7874 -0.4064)
			(stroke
				(width 0.1524)
				(type default)
			)
			(layer "F.SilkS")
		)
		(fp_line
			(start 0.7874 0.4064)
			(end -0.7874 0.4064)
			(stroke
				(width 0.1524)
				(type default)
			)
			(layer "F.SilkS")
		)
		(fp_line
			(start -0.7874 -0.4064)
			(end 0.7874 -0.4064)
			(stroke
				(width 0.1524)
				(type default)
			)
			(layer "F.SilkS")
		)
		(fp_line
			(start 0.7874 -0.4064)
			(end 0.7874 0.4064)
			(stroke
				(width 0.1524)
				(type default)
			)
			(layer "F.SilkS")
		)
		(fp_line
			(start -0.67945 0.3048)
			(end -0.67945 -0.305054)
			(stroke
				(width 0.1)
				(type default)
			)
			(layer "F.Fab")
		)
		(fp_line
			(start -0.12065 0.3048)
			(end -0.67945 0.3048)
			(stroke
				(width 0.1)
				(type default)
			)
			(layer "F.Fab")
		)
		(fp_line
			(start 0.120396 0.3048)
			(end 0.120396 0.2794)
			(stroke
				(width 0.1)
				(type default)
			)
			(layer "F.Fab")
		)
		(fp_line
			(start 0.67945 0.3048)
			(end 0.120396 0.3048)
			(stroke
				(width 0.1)
				(type default)
			)
			(layer "F.Fab")
		)
		(fp_line
			(start -0.12065 0.2794)
			(end -0.12065 0.3048)
			(stroke
				(width 0.1)
				(type default)
			)
			(layer "F.Fab")
		)
		(fp_line
			(start 0.120396 0.2794)
			(end -0.12065 0.2794)
			(stroke
				(width 0.1)
				(type default)
			)
			(layer "F.Fab")
		)
		(fp_line
			(start -0.12065 -0.2794)
			(end 0.12065 -0.2794)
			(stroke
				(width 0.1)
				(type default)
			)
			(layer "F.Fab")
		)
		(fp_line
			(start 0.12065 -0.2794)
			(end 0.12065 -0.3048)
			(stroke
				(width 0.1)
				(type default)
			)
			(layer "F.Fab")
		)
		(fp_line
			(start 0.12065 -0.3048)
			(end 0.67945 -0.3048)
			(stroke
				(width 0.1)
				(type default)
			)
			(layer "F.Fab")
		)
		(fp_line
			(start 0.67945 -0.3048)
			(end 0.67945 0.3048)
			(stroke
				(width 0.1)
				(type default)
			)
			(layer "F.Fab")
		)
		(fp_line
			(start -0.67945 -0.305054)
			(end -0.12065 -0.305054)
			(stroke
				(width 0.1)
				(type default)
			)
			(layer "F.Fab")
		)
		(fp_line
			(start -0.12065 -0.305054)
			(end -0.12065 -0.2794)
			(stroke
				(width 0.1)
				(type default)
			)
			(layer "F.Fab")
		)
		(pad "1" smd circle
			(at -0.40005 0 270)
			(size 0 0)
			(layers "F.Cu" "F.Mask" "F.Paste")
			(net "HDT_HDR_TDI")
		)
		(pad "2" smd circle
			(at 0.40005 0 270)
			(size 0 0)
			(layers "F.Cu" "F.Mask" "F.Paste")
			(net "GND")
		)
	)
	(footprint ""
		(layer "F.Cu")
		(at 56.50992 -31.664148)
		(property "Reference" "R3235"
			(at 0 0 0)
			(layer "F.SilkS")
			(hide yes)
			(effects
				(font
					(size 1.27 1.27)
				)
			)
		)
		(property "Value" ""
			(at 0 0 0)
			(layer "F.Fab")
			(effects
				(font
					(size 1.27 1.27)
				)
			)
		)
		(duplicate_pad_numbers_are_jumpers no)
		(fp_line
			(start -0.7874 -0.4064)
			(end 0.7874 -0.4064)
			(stroke
				(width 0.1524)
				(type default)
			)
			(layer "F.SilkS")
		)
		(fp_line
			(start -0.7874 0.4064)
			(end -0.7874 -0.4064)
			(stroke
				(width 0.1524)
				(type default)
			)
			(layer "F.SilkS")
		)
		(fp_line
			(start 0.7874 -0.4064)
			(end 0.7874 0.4064)
			(stroke
				(width 0.1524)
				(type default)
			)
			(layer "F.SilkS")
		)
		(fp_line
			(start 0.7874 0.4064)
			(end -0.7874 0.4064)
			(stroke
				(width 0.1524)
				(type default)
			)
			(layer "F.SilkS")
		)
		(fp_line
			(start -0.67945 -0.305054)
			(end -0.12065 -0.305054)
			(stroke
				(width 0.1)
				(type default)
			)
			(layer "F.Fab")
		)
		(fp_line
			(start -0.67945 0.3048)
			(end -0.67945 -0.305054)
			(stroke
				(width 0.1)
				(type default)
			)
			(layer "F.Fab")
		)
		(fp_line
			(start -0.12065 -0.305054)
			(end -0.12065 -0.2794)
			(stroke
				(width 0.1)
				(type default)
			)
			(layer "F.Fab")
		)
		(fp_line
			(start -0.12065 -0.2794)
			(end 0.12065 -0.2794)
			(stroke
				(width 0.1)
				(type default)
			)
			(layer "F.Fab")
		)
		(fp_line
			(start -0.12065 0.2794)
			(end -0.12065 0.3048)
			(stroke
				(width 0.1)
				(type default)
			)
			(layer "F.Fab")
		)
		(fp_line
			(start -0.12065 0.3048)
			(end -0.67945 0.3048)
			(stroke
				(width 0.1)
				(type default)
			)
			(layer "F.Fab")
		)
		(fp_line
			(start 0.120396 0.2794)
			(end -0.12065 0.2794)
			(stroke
				(width 0.1)
				(type default)
			)
			(layer "F.Fab")
		)
		(fp_line
			(start 0.120396 0.3048)
			(end 0.120396 0.2794)
			(stroke
				(width 0.1)
				(type default)
			)
			(layer "F.Fab")
		)
		(fp_line
			(start 0.12065 -0.3048)
			(end 0.67945 -0.3048)
			(stroke
				(width 0.1)
				(type default)
			)
			(layer "F.Fab")
		)
		(fp_line
			(start 0.12065 -0.2794)
			(end 0.12065 -0.3048)
			(stroke
				(width 0.1)
				(type default)
			)
			(layer "F.Fab")
		)
		(fp_line
			(start 0.67945 -0.3048)
			(end 0.67945 0.3048)
			(stroke
				(width 0.1)
				(type default)
			)
			(layer "F.Fab")
		)
		(fp_line
			(start 0.67945 0.3048)
			(end 0.120396 0.3048)
			(stroke
				(width 0.1)
				(type default)
			)
			(layer "F.Fab")
		)
		(pad "1" smd circle
			(at -0.40005 0)
			(size 0 0)
			(layers "F.Cu" "F.Mask" "F.Paste")
			(net "RST_HP_OCP_V3_2_R_N")
		)
		(pad "2" smd circle
			(at 0.40005 0)
			(size 0 0)
			(layers "F.Cu" "F.Mask" "F.Paste")
			(net "GND")
		)
	)
)
